(kicad_pcb
	(version 20260206)
	(generator "pcbnew")
	(generator_version "10.0")
	(general
		(thickness 1.6)
		(legacy_teardrops no)
	)
	(paper "A4")
	(title_block
		(title "01162023_DA0F0TEBIF0_F0T_Expander_BD_F_brd_V02_OCP.brd")
		(comment 1 "Grand Teton / footprints 1557-1563 of 9728")
	)
	(layers
		(0 "F.Cu" signal "TOP")
		(4 "In1.Cu" signal "GND")
		(6 "In2.Cu" signal "VCC")
		(8 "In3.Cu" signal "VCC1")
		(10 "In4.Cu" signal "GND1")
		(12 "In5.Cu" signal "IN1")
		(14 "In6.Cu" signal "GND2")
		(16 "In7.Cu" signal "IN2")
		(18 "In8.Cu" signal "GND3")
		(20 "In9.Cu" signal "IN3")
		(22 "In10.Cu" signal "GND4")
		(24 "In11.Cu" signal "IN4")
		(26 "In12.Cu" signal "GND5")
		(28 "In13.Cu" signal "IN5")
		(30 "In14.Cu" signal "GND6")
		(32 "In15.Cu" signal "IN6")
		(34 "In16.Cu" signal "GND7")
		(2 "B.Cu" signal "BOTTOM")
		(9 "F.Adhes" user "F.Adhesive")
		(11 "B.Adhes" user "B.Adhesive")
		(13 "F.Paste" user "Package Geometry/Pastemask Top")
		(15 "B.Paste" user "Package Geometry/Pastemask Bottom")
		(5 "F.SilkS" user "Ref Des/Silkscreen Top")
		(7 "B.SilkS" user "Ref Des/Silkscreen Bottom")
		(1 "F.Mask" user "Board Geometry/Soldermask Top")
		(3 "B.Mask" user "Board Geometry/Soldermask Bottom")
		(17 "Dwgs.User" user "User.Drawings")
		(19 "Cmts.User" user "User.Comments")
		(21 "Eco1.User" user "User.Eco1")
		(23 "Eco2.User" user "User.Eco2")
		(25 "Edge.Cuts" user "Board Geometry/Outline")
		(27 "Margin" user)
		(31 "F.CrtYd" user "Package Geometry/Place Bound Top")
		(29 "B.CrtYd" user "Package Geometry/Place Bound Bottom")
		(35 "F.Fab" user "Ref Des/Assembly Top")
		(33 "B.Fab" user "Ref Des/Assembly Bottom")
	)
	(footprint ""
		(layer "F.Cu")
		(at 147.107402 -260.639814 -90)
		(property "Reference" "C3210"
			(at 0 0 270)
			(layer "F.SilkS")
			(hide yes)
			(effects
				(font
					(size 1.27 1.27)
				)
			)
		)
		(property "Value" ""
			(at 0 0 270)
			(layer "F.Fab")
			(effects
				(font
					(size 1.27 1.27)
				)
			)
		)
		(duplicate_pad_numbers_are_jumpers no)
		(fp_line
			(start -0.299974 0.150114)
			(end -0.299974 -0.150114)
			(stroke
				(width 0.1)
				(type default)
			)
			(layer "F.Fab")
		)
		(fp_line
			(start 0.299974 0.150114)
			(end -0.299974 0.150114)
			(stroke
				(width 0.1)
				(type default)
			)
			(layer "F.Fab")
		)
		(fp_line
			(start -0.299974 -0.150114)
			(end 0.299974 -0.150114)
			(stroke
				(width 0.1)
				(type default)
			)
			(layer "F.Fab")
		)
		(fp_line
			(start 0.299974 -0.150114)
			(end 0.299974 0.150114)
			(stroke
				(width 0.1)
				(type default)
			)
			(layer "F.Fab")
		)
		(pad "1" smd rect
			(at -0.2667 0 270)
			(size 0.3048 0.381)
			(layers "F.Cu" "F.Mask" "F.Paste")
			(net "P1V8_PLL0_PEX1")
		)
		(pad "2" smd rect
			(at 0.2667 0 270)
			(size 0.3048 0.381)
			(layers "F.Cu" "F.Mask" "F.Paste")
			(net "GND")
		)
	)
	(footprint ""
		(layer "F.Cu")
		(at 368.734594 -30.03169 180)
		(property "Reference" "C703"
			(at 0 0 180)
			(layer "F.SilkS")
			(hide yes)
			(effects
				(font
					(size 1.27 1.27)
				)
			)
		)
		(property "Value" ""
			(at 0 0 180)
			(layer "F.Fab")
			(effects
				(font
					(size 1.27 1.27)
				)
			)
		)
		(duplicate_pad_numbers_are_jumpers no)
		(fp_line
			(start 0.299974 0.150114)
			(end -0.299974 0.150114)
			(stroke
				(width 0.1)
				(type default)
			)
			(layer "F.Fab")
		)
		(fp_line
			(start 0.299974 -0.150114)
			(end 0.299974 0.150114)
			(stroke
				(width 0.1)
				(type default)
			)
			(layer "F.Fab")
		)
		(fp_line
			(start -0.299974 0.150114)
			(end -0.299974 -0.150114)
			(stroke
				(width 0.1)
				(type default)
			)
			(layer "F.Fab")
		)
		(fp_line
			(start -0.299974 -0.150114)
			(end 0.299974 -0.150114)
			(stroke
				(width 0.1)
				(type default)
			)
			(layer "F.Fab")
		)
		(pad "1" smd rect
			(at -0.2667 0 180)
			(size 0.3048 0.381)
			(layers "F.Cu" "F.Mask" "F.Paste")
			(net "P5E_PEX3_STN2_TX_DN<45>")
		)
		(pad "2" smd rect
			(at 0.2667 0 180)
			(size 0.3048 0.381)
			(layers "F.Cu" "F.Mask" "F.Paste")
			(net "P5E_PEX3_STN2_TX_C_DN<45>")
		)
	)
	(footprint ""
		(layer "F.Cu")
		(at 343.567004 -343.952322 90)
		(property "Reference" "C579"
			(at 0 0 90)
			(layer "F.SilkS")
			(hide yes)
			(effects
				(font
					(size 1.27 1.27)
				)
			)
		)
		(property "Value" ""
			(at 0 0 90)
			(layer "F.Fab")
			(effects
				(font
					(size 1.27 1.27)
				)
			)
		)
		(duplicate_pad_numbers_are_jumpers no)
		(fp_line
			(start 0.299974 -0.150114)
			(end 0.299974 0.150114)
			(stroke
				(width 0.1)
				(type default)
			)
			(layer "F.Fab")
		)
		(fp_line
			(start -0.299974 -0.150114)
			(end 0.299974 -0.150114)
			(stroke
				(width 0.1)
				(type default)
			)
			(layer "F.Fab")
		)
		(fp_line
			(start 0.299974 0.150114)
			(end -0.299974 0.150114)
			(stroke
				(width 0.1)
				(type default)
			)
			(layer "F.Fab")
		)
		(fp_line
			(start -0.299974 0.150114)
			(end -0.299974 -0.150114)
			(stroke
				(width 0.1)
				(type default)
			)
			(layer "F.Fab")
		)
		(pad "1" smd rect
			(at -0.2667 0 90)
			(size 0.3048 0.381)
			(layers "F.Cu" "F.Mask" "F.Paste")
			(net "P5E_PEX2_STN6_TX_DP<97>")
		)
		(pad "2" smd rect
			(at 0.2667 0 90)
			(size 0.3048 0.381)
			(layers "F.Cu" "F.Mask" "F.Paste")
			(net "P5E_PEX2_STN6_TX_C_DP<97>")
		)
	)
	(footprint ""
		(layer "F.Cu")
		(at 74.647044 -54.3941)
		(property "Reference" "PU34"
			(at -1.744218 2.865628 0)
			(unlocked yes)
			(layer "F.SilkS")
			(effects
				(font
					(size 0.7874 0.5842)
					(thickness 0.1524)
				)
				(justify left)
			)
		)
		(property "Value" ""
			(at 0 0 0)
			(layer "F.Fab")
			(effects
				(font
					(size 1.27 1.27)
				)
			)
		)
		(duplicate_pad_numbers_are_jumpers no)
		(fp_line
			(start -1.943608 -1.549908)
			(end 1.943608 -1.549908)
			(stroke
				(width 0.1524)
				(type default)
			)
			(layer "F.SilkS")
		)
		(fp_line
			(start -1.943608 1.549908)
			(end -1.943608 -1.549908)
			(stroke
				(width 0.1524)
				(type default)
			)
			(layer "F.SilkS")
		)
		(fp_line
			(start 1.943608 -1.549908)
			(end 1.943608 1.549908)
			(stroke
				(width 0.1524)
				(type default)
			)
			(layer "F.SilkS")
		)
		(fp_line
			(start 1.943608 1.549908)
			(end -1.943608 1.549908)
			(stroke
				(width 0.1524)
				(type default)
			)
			(layer "F.SilkS")
		)
		(fp_poly
			(pts
				(xy -2.019808 -1.549908) (xy -1.257808 -1.549908) (xy -1.257808 -1.880108) (xy -2.019808 -1.880108)
			)
			(stroke
				(width 0)
				(type default)
			)
			(fill yes)
			(layer "F.SilkS")
		)
		(fp_line
			(start -1.549908 -1.549908)
			(end 1.549908 -1.549908)
			(stroke
				(width 0.1)
				(type default)
			)
			(layer "F.Fab")
		)
		(fp_line
			(start -1.549908 1.549908)
			(end -1.549908 -1.549908)
			(stroke
				(width 0.1)
				(type default)
			)
			(layer "F.Fab")
		)
		(fp_line
			(start 1.549908 -1.549908)
			(end 1.549908 1.549908)
			(stroke
				(width 0.1)
				(type default)
			)
			(layer "F.Fab")
		)
		(fp_line
			(start 1.549908 1.549908)
			(end -1.549908 1.549908)
			(stroke
				(width 0.1)
				(type default)
			)
			(layer "F.Fab")
		)
		(fp_poly
			(pts
				(xy -2.019808 -1.549908) (xy -1.257808 -1.549908) (xy -1.257808 -1.880108) (xy -2.019808 -1.880108)
			)
			(stroke
				(width 0)
				(type default)
			)
			(fill yes)
			(layer "F.Fab")
		)
		(pad "1" smd rect
			(at -1.500124 -1.249934 270)
			(size 0.2794 0.6096)
			(layers "F.Cu" "F.Mask" "F.Paste")
			(net "P12V_SSD2_R")
		)
		(pad "2" smd rect
			(at -1.500124 -0.750062 270)
			(size 0.2794 0.6096)
			(layers "F.Cu" "F.Mask" "F.Paste")
			(net "P12V_SSD2_R")
		)
		(pad "3" smd rect
			(at -1.500124 -0.249936 270)
			(size 0.2794 0.6096)
			(layers "F.Cu" "F.Mask" "F.Paste")
			(net "P12V_SSD2_R")
		)
		(pad "4" smd rect
			(at -1.500124 0.249936 270)
			(size 0.2794 0.6096)
			(layers "F.Cu" "F.Mask" "F.Paste")
			(net "P12V_SSD2_R")
		)
		(pad "5" smd rect
			(at -1.500124 0.750062 270)
			(size 0.2794 0.6096)
			(layers "F.Cu" "F.Mask" "F.Paste")
			(net "P12V_SSD2_R")
		)
		(pad "6" smd rect
			(at -1.500124 1.249934 270)
			(size 0.2794 0.6096)
			(layers "F.Cu" "F.Mask" "F.Paste")
			(net "GND")
		)
		(pad "7" smd rect
			(at 1.500124 1.249934 270)
			(size 0.2794 0.6096)
			(layers "F.Cu" "F.Mask" "F.Paste")
			(net "P12V_SSD2_SS")
		)
		(pad "8" smd rect
			(at 1.500124 0.750062 270)
			(size 0.2794 0.6096)
			(layers "F.Cu" "F.Mask" "F.Paste")
			(net "PWRGD_P12V_SSD2")
		)
		(pad "9" smd rect
			(at 1.500124 0.249936 270)
			(size 0.2794 0.6096)
			(layers "F.Cu" "F.Mask" "F.Paste")
			(net "P12V_SSD2_OCP")
		)
		(pad "10" smd rect
			(at 1.500124 -0.249936 270)
			(size 0.2794 0.6096)
			(layers "F.Cu" "F.Mask" "F.Paste")
			(net "P5V_AUX")
		)
		(pad "11" smd rect
			(at 1.500124 -0.750062 270)
			(size 0.2794 0.6096)
			(layers "F.Cu" "F.Mask" "F.Paste")
			(net "SSD2_PWR_EN_R")
		)
		(pad "12" smd rect
			(at 1.500124 -1.249934 270)
			(size 0.2794 0.6096)
			(layers "F.Cu" "F.Mask" "F.Paste")
			(net "P12V_AUX")
		)
		(pad "13" smd rect
			(at 0 0)
			(size 1.9812 2.7178)
			(layers "F.Cu" "F.Mask" "F.Paste")
			(net "P12V_AUX")
		)
		(zone
			(layer "F.Cu")
			(hatch none 0.5)
			(connect_pads
				(clearance 0)
			)
			(min_thickness 0.25)
			(keepout
				(tracks not_allowed)
				(vias allowed)
				(pads allowed)
				(copperpour not_allowed)
				(footprints allowed)
			)
			(placement
				(enabled no)
				(sheetname "")
			)
			(fill
				(thermal_gap 0.5)
				(thermal_bridge_width 0.5)
				(island_removal_mode 0)
			)
			(polygon
				(pts
					(xy 75.790044 -55.9435) (xy 75.790044 -55.8165) (xy 75.790044 -52.8447) (xy 75.790044 -52.844192)
					(xy 73.504044 -52.844192) (xy 73.504044 -52.8447) (xy 73.504044 -52.9717) (xy 73.504044 -54.3941)
					(xy 73.605644 -54.3941) (xy 73.605644 -52.9717) (xy 75.688444 -52.9717) (xy 75.688444 -55.8165)
					(xy 73.605644 -55.8165) (xy 73.605644 -54.4195) (xy 73.504044 -54.4195) (xy 73.504044 -55.8165)
					(xy 73.504044 -55.9435) (xy 73.504044 -55.944008) (xy 75.790044 -55.944008)
				)
			)
		)
	)
	(footprint ""
		(layer "F.Cu")
		(at 117.226334 -39.73576 -90)
		(property "Reference" "R5551"
			(at 0 0 270)
			(layer "F.SilkS")
			(hide yes)
			(effects
				(font
					(size 1.27 1.27)
				)
			)
		)
		(property "Value" ""
			(at 0 0 270)
			(layer "F.Fab")
			(effects
				(font
					(size 1.27 1.27)
				)
			)
		)
		(duplicate_pad_numbers_are_jumpers no)
		(fp_line
			(start -0.7874 0.4064)
			(end -0.7874 -0.4064)
			(stroke
				(width 0.1524)
				(type default)
			)
			(layer "F.SilkS")
		)
		(fp_line
			(start 0.7874 0.4064)
			(end -0.7874 0.4064)
			(stroke
				(width 0.1524)
				(type default)
			)
			(layer "F.SilkS")
		)
		(fp_line
			(start -0.7874 -0.4064)
			(end 0.7874 -0.4064)
			(stroke
				(width 0.1524)
				(type default)
			)
			(layer "F.SilkS")
		)
		(fp_line
			(start 0.7874 -0.4064)
			(end 0.7874 0.4064)
			(stroke
				(width 0.1524)
				(type default)
			)
			(layer "F.SilkS")
		)
		(fp_line
			(start -0.67945 0.3048)
			(end -0.67945 -0.305054)
			(stroke
				(width 0.1)
				(type default)
			)
			(layer "F.Fab")
		)
		(fp_line
			(start -0.12065 0.3048)
			(end -0.67945 0.3048)
			(stroke
				(width 0.1)
				(type default)
			)
			(layer "F.Fab")
		)
		(fp_line
			(start 0.120396 0.3048)
			(end 0.120396 0.2794)
			(stroke
				(width 0.1)
				(type default)
			)
			(layer "F.Fab")
		)
		(fp_line
			(start 0.67945 0.3048)
			(end 0.120396 0.3048)
			(stroke
				(width 0.1)
				(type default)
			)
			(layer "F.Fab")
		)
		(fp_line
			(start -0.12065 0.2794)
			(end -0.12065 0.3048)
			(stroke
				(width 0.1)
				(type default)
			)
			(layer "F.Fab")
		)
		(fp_line
			(start 0.120396 0.2794)
			(end -0.12065 0.2794)
			(stroke
				(width 0.1)
				(type default)
			)
			(layer "F.Fab")
		)
		(fp_line
			(start -0.12065 -0.2794)
			(end 0.12065 -0.2794)
			(stroke
				(width 0.1)
				(type default)
			)
			(layer "F.Fab")
		)
		(fp_line
			(start 0.12065 -0.2794)
			(end 0.12065 -0.3048)
			(stroke
				(width 0.1)
				(type default)
			)
			(layer "F.Fab")
		)
		(fp_line
			(start 0.12065 -0.3048)
			(end 0.67945 -0.3048)
			(stroke
				(width 0.1)
				(type default)
			)
			(layer "F.Fab")
		)
		(fp_line
			(start 0.67945 -0.3048)
			(end 0.67945 0.3048)
			(stroke
				(width 0.1)
				(type default)
			)
			(layer "F.Fab")
		)
		(fp_line
			(start -0.67945 -0.305054)
			(end -0.12065 -0.305054)
			(stroke
				(width 0.1)
				(type default)
			)
			(layer "F.Fab")
		)
		(fp_line
			(start -0.12065 -0.305054)
			(end -0.12065 -0.2794)
			(stroke
				(width 0.1)
				(type default)
			)
			(layer "F.Fab")
		)
		(pad "1" smd circle
			(at -0.40005 0 270)
			(size 0 0)
			(layers "F.Cu" "F.Mask" "F.Paste")
			(net "P3V3_AUX")
		)
		(pad "2" smd circle
			(at 0.40005 0 270)
			(size 0 0)
			(layers "F.Cu" "F.Mask" "F.Paste")
			(net "SSD4_AUX_P3V3_EN")
		)
	)
	(footprint ""
		(layer "F.Cu")
		(at 52.243736 -47.92091)
		(property "Reference" "R515"
			(at 0 0 0)
			(layer "F.SilkS")
			(hide yes)
			(effects
				(font
					(size 1.27 1.27)
				)
			)
		)
		(property "Value" ""
			(at 0 0 0)
			(layer "F.Fab")
			(effects
				(font
					(size 1.27 1.27)
				)
			)
		)
		(duplicate_pad_numbers_are_jumpers no)
		(fp_line
			(start -0.7874 -0.4064)
			(end 0.7874 -0.4064)
			(stroke
				(width 0.1524)
				(type default)
			)
			(layer "F.SilkS")
		)
		(fp_line
			(start -0.7874 0.4064)
			(end -0.7874 -0.4064)
			(stroke
				(width 0.1524)
				(type default)
			)
			(layer "F.SilkS")
		)
		(fp_line
			(start 0.7874 -0.4064)
			(end 0.7874 0.4064)
			(stroke
				(width 0.1524)
				(type default)
			)
			(layer "F.SilkS")
		)
		(fp_line
			(start 0.7874 0.4064)
			(end -0.7874 0.4064)
			(stroke
				(width 0.1524)
				(type default)
			)
			(layer "F.SilkS")
		)
		(fp_line
			(start -0.67945 -0.305054)
			(end -0.12065 -0.305054)
			(stroke
				(width 0.1)
				(type default)
			)
			(layer "F.Fab")
		)
		(fp_line
			(start -0.67945 0.3048)
			(end -0.67945 -0.305054)
			(stroke
				(width 0.1)
				(type default)
			)
			(layer "F.Fab")
		)
		(fp_line
			(start -0.12065 -0.305054)
			(end -0.12065 -0.2794)
			(stroke
				(width 0.1)
				(type default)
			)
			(layer "F.Fab")
		)
		(fp_line
			(start -0.12065 -0.2794)
			(end 0.12065 -0.2794)
			(stroke
				(width 0.1)
				(type default)
			)
			(layer "F.Fab")
		)
		(fp_line
			(start -0.12065 0.2794)
			(end -0.12065 0.3048)
			(stroke
				(width 0.1)
				(type default)
			)
			(layer "F.Fab")
		)
		(fp_line
			(start -0.12065 0.3048)
			(end -0.67945 0.3048)
			(stroke
				(width 0.1)
				(type default)
			)
			(layer "F.Fab")
		)
		(fp_line
			(start 0.120396 0.2794)
			(end -0.12065 0.2794)
			(stroke
				(width 0.1)
				(type default)
			)
			(layer "F.Fab")
		)
		(fp_line
			(start 0.120396 0.3048)
			(end 0.120396 0.2794)
			(stroke
				(width 0.1)
				(type default)
			)
			(layer "F.Fab")
		)
		(fp_line
			(start 0.12065 -0.3048)
			(end 0.67945 -0.3048)
			(stroke
				(width 0.1)
				(type default)
			)
			(layer "F.Fab")
		)
		(fp_line
			(start 0.12065 -0.2794)
			(end 0.12065 -0.3048)
			(stroke
				(width 0.1)
				(type default)
			)
			(layer "F.Fab")
		)
		(fp_line
			(start 0.67945 -0.3048)
			(end 0.67945 0.3048)
			(stroke
				(width 0.1)
				(type default)
			)
			(layer "F.Fab")
		)
		(fp_line
			(start 0.67945 0.3048)
			(end 0.120396 0.3048)
			(stroke
				(width 0.1)
				(type default)
			)
			(layer "F.Fab")
		)
		(pad "1" smd circle
			(at -0.40005 0)
			(size 0 0)
			(layers "F.Cu" "F.Mask" "F.Paste")
			(net "P3V3_AUX")
		)
		(pad "2" smd circle
			(at 0.40005 0)
			(size 0 0)
			(layers "F.Cu" "F.Mask" "F.Paste")
			(net "SSD_0_7_ADC_ALERT_N")
		)
	)
	(footprint ""
		(layer "F.Cu")
		(at 241.216434 -250.759722 -90)
		(property "Reference" "R6227"
			(at 0 0 270)
			(layer "F.SilkS")
			(hide yes)
			(effects
				(font
					(size 1.27 1.27)
				)
			)
		)
		(property "Value" ""
			(at 0 0 270)
			(layer "F.Fab")
			(effects
				(font
					(size 1.27 1.27)
				)
			)
		)
		(duplicate_pad_numbers_are_jumpers no)
		(fp_line
			(start -0.7874 0.4064)
			(end -0.7874 -0.4064)
			(stroke
				(width 0.1524)
				(type default)
			)
			(layer "F.SilkS")
		)
		(fp_line
			(start 0.7874 0.4064)
			(end -0.7874 0.4064)
			(stroke
				(width 0.1524)
				(type default)
			)
			(layer "F.SilkS")
		)
		(fp_line
			(start -0.7874 -0.4064)
			(end 0.7874 -0.4064)
			(stroke
				(width 0.1524)
				(type default)
			)
			(layer "F.SilkS")
		)
		(fp_line
			(start 0.7874 -0.4064)
			(end 0.7874 0.4064)
			(stroke
				(width 0.1524)
				(type default)
			)
			(layer "F.SilkS")
		)
		(fp_line
			(start -0.67945 0.3048)
			(end -0.67945 -0.305054)
			(stroke
				(width 0.1)
				(type default)
			)
			(layer "F.Fab")
		)
		(fp_line
			(start -0.12065 0.3048)
			(end -0.67945 0.3048)
			(stroke
				(width 0.1)
				(type default)
			)
			(layer "F.Fab")
		)
		(fp_line
			(start 0.120396 0.3048)
			(end 0.120396 0.2794)
			(stroke
				(width 0.1)
				(type default)
			)
			(layer "F.Fab")
		)
		(fp_line
			(start 0.67945 0.3048)
			(end 0.120396 0.3048)
			(stroke
				(width 0.1)
				(type default)
			)
			(layer "F.Fab")
		)
		(fp_line
			(start -0.12065 0.2794)
			(end -0.12065 0.3048)
			(stroke
				(width 0.1)
				(type default)
			)
			(layer "F.Fab")
		)
		(fp_line
			(start 0.120396 0.2794)
			(end -0.12065 0.2794)
			(stroke
				(width 0.1)
				(type default)
			)
			(layer "F.Fab")
		)
		(fp_line
			(start -0.12065 -0.2794)
			(end 0.12065 -0.2794)
			(stroke
				(width 0.1)
				(type default)
			)
			(layer "F.Fab")
		)
		(fp_line
			(start 0.12065 -0.2794)
			(end 0.12065 -0.3048)
			(stroke
				(width 0.1)
				(type default)
			)
			(layer "F.Fab")
		)
		(fp_line
			(start 0.12065 -0.3048)
			(end 0.67945 -0.3048)
			(stroke
				(width 0.1)
				(type default)
			)
			(layer "F.Fab")
		)
		(fp_line
			(start 0.67945 -0.3048)
			(end 0.67945 0.3048)
			(stroke
				(width 0.1)
				(type default)
			)
			(layer "F.Fab")
		)
		(fp_line
			(start -0.67945 -0.305054)
			(end -0.12065 -0.305054)
			(stroke
				(width 0.1)
				(type default)
			)
			(layer "F.Fab")
		)
		(fp_line
			(start -0.12065 -0.305054)
			(end -0.12065 -0.2794)
			(stroke
				(width 0.1)
				(type default)
			)
			(layer "F.Fab")
		)
		(pad "1" smd circle
			(at -0.40005 0 270)
			(size 0 0)
			(layers "F.Cu" "F.Mask" "F.Paste")
			(net "BIC_FWSPICK")
		)
		(pad "2" smd circle
			(at 0.40005 0 270)
			(size 0 0)
			(layers "F.Cu" "F.Mask" "F.Paste")
			(net "BIC_FWSPICK_IOEXP")
		)
	)
)
